# BASEBOARD_FAB2 (Tioga Pass) — schematic parts with pin connectivity, parts 2673–2832 of 4751; source: Cadence DE-HDL packaged netlist (pstxprt.dat, pstxnet.dat, pstchip.dat)

R1L28  RES  4.75K 1% EMPTY  pkg 0402  page 111 : 1 = P3V3_STBY ; 2 = FM_DEBUG_RST_BTN_R1_N
R1L29  RES  33.2 1% CHIP  pkg 0402  page 111 : 1 = FM_DEBUG_RST_BTN_R1_N ; 2 = FM_DEBUG_RST_BTN_N
R1L30  RES  10.0 1% CHIP  pkg 0402  page 155 : 1 = LED_POSTCODE_1 ; 2 = LED_POSTCODE_1_R
R1L31  RES  200.0 1% CHIP  pkg 0402  page 175 : 1 = FP_PWR_BTN_R_N ; 2 = FP_PWR_BTN_R1_N
R1L32  RES  10.0 1% CHIP  pkg 0402  page 155 : 1 = LED_POSTCODE_0 ; 2 = LED_POSTCODE_0_R
R1L33  RES  221 1.0% CHIP  pkg 0402  page 175 : 1 = FM_BEEP_LED_P ; 2 = P3V3_STBY
R1L36  RES  1.00K 1% CHIP  pkg 0402  page 168 : 1 = P3V3_STBY ; 2 = FM_DB_PRESENT
R1L37  RES  301.0 1% CHIP  pkg 0402  page 177 : 1 = P5V_STBY ; 2 = LED_P5V_STBY
R1L38  RES  1.00K 1% CHIP  pkg 0402  page 168 : 1 = P3V3_STBY ; 2 = FM_POST_CARD_PRES_BMC_N
R1L39  RES  100.0 1% CHIP  pkg 0402  page 112 : 1 = P1V05_PCH_STBY ; 2 = XDP_PRDY_N
R1L41  RES  100.0 1% CHIP  pkg 0402  page 112 : 1 = P1V05_PCH_STBY ; 2 = XDP_PREQ_N
R1L43  RES  330 5% CHIP  pkg 0402  page 158 : 1 = FM_UARTSW_LSB_R_N ; 2 = P3V3_STBY
R1L44  RES  330 5% CHIP  pkg 0402  page 158 : 1 = FM_UARTSW_MSB_R_N ; 2 = P3V3_STBY
R1M3  RES  100.0 1% CHIP  pkg 0402  page 112 : 1 = PVCCIO_CPU0 ; 2 = XDP_CPU_PRDY_N
R1M4  RES  100.0 1% CHIP  pkg 0402  page 112 : 1 = PVCCIO_CPU0 ; 2 = XDP_CPU_PREQ_N
R1M5  RES  0.0 5% CHIP  pkg 0402  page 176 : 1 = USB2_P01_DP ; 2 = USB2_P01_ESD_DP
R1M6  RES  0.0 5% CHIP  pkg 0402  page 176 : 1 = USB2_P01_DN ; 2 = USB2_P01_ESD_DN
R1M8  RES  20.0 1% CHIP  pkg 0402  page 167 : 1 = SMB_SENSOR_TMP421_1_SCL ; 2 = SMB_SENSOR_STBY_LVC3_SCL
R1M9  RES  20.0 1% CHIP  pkg 0402  page 167 : 1 = SMB_SENSOR_TMP421_1_SDA ; 2 = SMB_SENSOR_STBY_LVC3_SDA
R1M10  RES  0.0 5% CHIP  pkg 0402  page 177 : 1 = LED_PCH_SATA_HDD_N ; 2 = LED_SATA_ACT_R_N
R1M11  RES  10.0K 1% CHIP  pkg 0402  page 177 : 1 = P3V3 ; 2 = LED_SATA_ACT_R_N
R1M12  RES  10.0K 1% CHIP  pkg 0402  page 177 : 1 = P3V3 ; 2 = LED_SAS_ACT_R_N
R1M13  RES  0.0 5% CHIP  pkg 0402  page 177 : 1 = LED_PCH_SSATA_HDD_N ; 2 = LED_SAS_ACT_R_N
R1M14  RES  200.0 1% CHIP  pkg 0402  page 186 : 1 = RST_PCIE_CPU_DEV0_N ; 2 = RST_PCIE_CPU_DEV0_R_N
R1M15  RES  0.0 5% CHIP  pkg 0402  page 186 : 1 = RMII_BMC_OCP_CRSDV ; 2 = RMII_BMC_OCP_CRSDV_R
R1M16  RES  0.0 5% CHIP  pkg 0402  page 186 : 1 = RMII_BMC_OCP_RXD1 ; 2 = RMII_BMC_OCP_RXD1_R
R1M17  RES  0.0 5% CHIP  pkg 0402  page 186 : 1 = RMII_BMC_OCP_RXD0 ; 2 = RMII_BMC_OCP_RXD0_R
R1M18  RES  0.0 5% CHIP  pkg 0402  page 186 : 1 = RMII_BMC_OCP_RXER_R ; 2 = RMII_BMC_OCP_RXER
R1M19  RES  1.00K 1% CHIP  pkg 0402  page 113 : 1 = P1V8_MCP_CPU0 ; 2 = JTAG_MCP_TMS
R1M20  RES  1.00K 1% CHIP  pkg 0402  page 113 : 1 = P1V8_MCP_CPU0 ; 2 = JTAG_MCP_MUX_TDI
R1M21  RES  1.00K 1% CHIP  pkg 0402  page 113 : 1 = P1V8_MCP_CPU0 ; 2 = JTAG_MCP_TRST_N
R1M22  RES  49.9 1% CHIP  pkg 0402  page 113 : 1 = JTAG_MCP_TMS_R1 ; 2 = JTAG_MCP_TMS
R1M23  RES  1.00K 1% EMPTY  pkg 0402  page 113 : 1 = JTAG_MCP_TRST_N ; 2 = GND
R1M24  RES  10.0K 1% CHIP  pkg 0402  page 176 : 1 = P3V3_STBY ; 2 = FM_OC0_USB_N
R1M25  RES  10.0K 1% CHIP  pkg 0402  page 176 : 1 = FM_USB_P0_EN_R_N ; 2 = GND
R1R1  RES  0.0 5% CHIP  pkg 0402  page 139 : 1 = RST_PLTRST_N ; 2 = RST_PLTRST_SPRV_R_N
R1R3  RES  3.32K 1% CHIP  pkg 0402  page 140 : 1 = P3V3_STBY ; 2 = PU_NV_WP_N
R1R5  RES  4.75K 1% CHIP  pkg 0402  page 170 : 1 = P3V3_STBY ; 2 = FM_FAST_PROCHOT_THROTTLE_DLY_BU
R1R6  RES  3.32K 1% EMPTY  pkg 0402  page 140 : 1 = SPI_NIC_MOSI ; 2 = GND
R1R7  RES  20.0K 1% CHIP  pkg 0402  page 140 : 1 = P3V3_STBY ; 2 = SPI_NIC_MOSI
R1R8  RES  0.0 5% CHIP  pkg 0402  page 170 : 1 = FM_THROTTLE_R1_N ; 2 = FM_THROTTLE_N
R1R9  RES  3.32K 1% CHIP  pkg 0402  page 140 : 1 = P3V3_STBY ; 2 = PU_NV_HOLD_N
R1R12  RES  10.0K 1% CHIP  pkg 0402  page 139 : 1 = CLK_50M_CKMNG_SPRVLLE ; 2 = GND
R1R15  RES  0 5.0% CHIP  pkg 0603  page 139 : 1 = P0V9_LAN ; 2 = P0V9_LAN_I210
R1R16  RES  2.21K 1% CHIP  pkg 0402  page 188 : 1 = P3V3_STBY ; 2 = SMB_PCH_MEZZ_LOM2_SCL
R1R17  RES  2.21K 1% CHIP  pkg 0402  page 188 : 1 = P3V3_STBY ; 2 = SMB_PCH_MEZZ_LOM2_SDA
R1R18  RES  2.21K 1% CHIP  pkg 0402  page 188 : 1 = P3V3_STBY ; 2 = SMB_PCH_MEZZ_LOM0_SCL
R1R19  RES  2.21K 1% CHIP  pkg 0402  page 188 : 1 = P3V3_STBY ; 2 = SMB_PCH_MEZZ_LOM0_SDA
R1R20  RES  2.21K 1% CHIP  pkg 0402  page 188 : 1 = P3V3_STBY ; 2 = SMB_PCH_MEZZ_LOM1_SCL
R1R21  RES  2.21K 1% CHIP  pkg 0402  page 188 : 1 = P3V3_STBY ; 2 = SMB_PCH_MEZZ_LOM1_SDA
R1R22  RES  2.21K 1% CHIP  pkg 0402  page 188 : 1 = P3V3_STBY ; 2 = SMB_PCH_MEZZ_LOM3_SDA
R1R23  RES  2.21K 1% CHIP  pkg 0402  page 188 : 1 = P3V3_STBY ; 2 = SMB_PCH_MEZZ_LOM3_SCL
R1T1  RES  10.0K 1% CHIP  pkg 0402  page 139 : 1 = RMII_BMC_PCH_SPRNGVLLE_CRSDV ; 2 = GND
R1T2  RES  665 1.0% CHIP  pkg 0402  page 160 : 1 = P3V3_STBY ; 2 = SMB_SLOTX24_STBY_LVC3_SCL_R
R1T3  RES  665 1.0% CHIP  pkg 0402  page 160 : 1 = P3V3_STBY ; 2 = SMB_SLOTX24_STBY_LVC3_SDA_R
R1T4  RES  2.7K 1% CHIP  pkg 0402  page 164 : 1 = P3V3_STBY ; 2 = FM_BOARD_REV_ID0
R1T5  RES  2.7K 1% EMPTY  pkg 0402  page 164 : 1 = P3V3_STBY ; 2 = FM_BOARD_REV_ID2
R1T6  RES  2.7K 1% CHIP  pkg 0402  page 164 : 1 = P3V3_STBY ; 2 = FM_BOARD_REV_ID1
R1T7  RES  20.0 1% CHIP  pkg 0402  page 160 : 1 = SMB_SLOTX24_STBY_LVC3_SCL_R ; 2 = SMB_SLOTX24_BMC_STBY_LVC3_SCL
R1T8  RES  20.0 1% CHIP  pkg 0402  page 160 : 1 = SMB_SLOTX24_STBY_LVC3_SDA_R ; 2 = SMB_SLOTX24_BMC_STBY_LVC3_SDA
R1T9  RES  22.1 1.0% CHIP  pkg 0402  page 239 : 1 = PWRGD_P1V2_BMC_STBY_R ; 2 = PWRGD_P1V2_BMC_STBY
R1T10  RES  1.00K 1% CHIP  pkg 0402  page 164 : 1 = FM_BOARD_REV_ID0 ; 2 = GND
R1T11  RES  1.00K 1% CHIP  pkg 0402  page 164 : 1 = FM_BOARD_REV_ID2 ; 2 = GND
R1T12  RES  1.00K 1% CHIP  pkg 0402  page 164 : 1 = FM_BOARD_REV_ID1 ; 2 = GND
R1T15  RES  0.0 5% EMPTY  pkg 0402  page 145 : 1 = FM_BMC_ONCTL_N ; 2 = FM_BMC_ONCTL_R_N
R1T23  RES  0.0 5% EMPTY  pkg 0402  page 145 : 1 = FM_BMC_ONCTL_R_N ; 2 = GND
R1T24  RES  0.0 5% EMPTY  pkg 0402  page 147 : 1 = PUMP_TACH0 ; 2 = FM_FLASH_DESC_OVERRIDE
R1T25  RES  8.2K 1% CHIP  pkg 0402  page 146 : 1 = A_USB2BVRES ; 2 = GND
R1T26  RES  8.2K 1% CHIP  pkg 0402  page 146 : 1 = A_USB2AVRES ; 2 = GND
R1T27  RES  240 1.0% CHIP  pkg 0402  page 143 : 1 = GND ; 2 = BMC_MIOZ
R1T28  RES  49.9 1% CHIP  pkg 0402  page 151 : 1 = BMC_M_CLK_DN ; 2 = BMC_M_CLK
R1T29  RES  1.00K 1% CHIP  pkg 0402  page 151 : 1 = BMC_M_VREFCA ; 2 = GND
R1T30  RES  1.00K 1% CHIP  pkg 0402  page 151 : 1 = P1V2_AUX_BMC ; 2 = BMC_M_VREFCA
R1T32  RES  0 5.0% CHIP  pkg 0603  page 139 : 1 = P1V5_LAN ; 2 = P1V5_LAN_I210
R1T33  RES  0 5.0% EMPTY  pkg 0603  page 139 : 1 = P1V5_LAN ; 2 = P3V3_STBY_P1V5_LAN_I210
R1T34  RES  0 5.0% CHIP  pkg 0603  page 139 : 1 = P3V3_STBY ; 2 = P3V3_STBY_P1V5_LAN_I210
R1T35  RES  0.0 5% EMPTY  pkg 0402  page 93 : 1 = FM_CPU0_PROCHOT_LVT3_N ; 2 = FM_CPU0_PROCHOT_PCH_N
R1T36  RES  0.0 5% CHIP  pkg 0402  page 93 : 1 = FM_CPU0_PROCHOT_LVT3_N ; 2 = FM_CPU0_PROCHOT_LVT3_BMC_N
R1T37  RES  0.0 5% CHIP  pkg 0402  page 93 : 1 = FM_CPU1_PROCHOT_LVT3_N ; 2 = FM_CPU1_PROCHOT_LVT3_BMC_N
R1T38  RES  0.0 5% EMPTY  pkg 0402  page 93 : 1 = FM_CPU1_PROCHOT_LVT3_N ; 2 = FM_CPU1_PROCHOT_PCH_N
R1T40  RES  49.9 1% CHIP  pkg 0402  page 151 : 1 = BMC_M_CLK_DP ; 2 = BMC_M_CLK
R1U1  RES  100.0K 1% CHIP  pkg 0402  page 147 : 1 = FAN_TACH3 ; 2 = GND
R1U2  RES  100.0K 1% CHIP  pkg 0402  page 147 : 1 = FAN_TACH2 ; 2 = GND
R1U4  RES  100.0K 1% CHIP  pkg 0402  page 147 : 1 = FAN_TACH1 ; 2 = GND
R1U5  RES  100.0K 1% CHIP  pkg 0402  page 147 : 1 = FAN_TACH0 ; 2 = GND
R1U6  RES  10.0K 1% CHIP  pkg 0402  page 154 : 1 = FM_BIOS_SPI_BMC_CTRL ; 2 = GND
R1U7  RES  10.0K 1% CHIP  pkg 0402  page 146 : 1 = GND ; 2 = PD_SP_ENTEST
R1U8  RES  0.0 5% CHIP  pkg 0402  page 159 : 1 = SMB_VR_STBY_LVC3_SDA_R ; 2 = SMB_VR_STBY_LVC3_SDA
R1U9  RES  20.0 1% CHIP  pkg 0402  page 159 : 1 = SMB_SMLINK0_STBY_LVC3_SCL_R ; 2 = SMB_SMLINK0_STBY_LVC3_SCL
R1U10  RES  20.0 1% CHIP  pkg 0402  page 159 : 1 = SMB_SMLINK0_STBY_LVC3_SDA_R ; 2 = SMB_SMLINK0_STBY_LVC3_SDA
R1U11  RES  0.0 5% CHIP  pkg 0402  page 159 : 1 = SMB_VR_STBY_LVC3_SCL_R ; 2 = SMB_VR_STBY_LVC3_SCL
R1U12  RES  51 5.0% CHIP  pkg 0402  page 144 : 1 = SGPIO_BMC_LD_R_N ; 2 = SGPIO_BMC_LD_N
R1U13  RES  51 5.0% CHIP  pkg 0402  page 144 : 1 = SGPIO_BMC_DOUT_R ; 2 = SGPIO_BMC_DOUT
R1U14  RES  51 5.0% CHIP  pkg 0402  page 144 : 1 = SGPIO_BMC_CLK_R ; 2 = SGPIO_BMC_CLK
R1U15  RES  1.00K 1% CHIP  pkg 0402  page 164 : 1 = FM_BOARD_SKU_ID3 ; 2 = GND
R1U16  RES  1.00K 1% CHIP  pkg 0402  page 164 : 1 = FM_BOARD_SKU_ID1 ; 2 = GND
R1U17  RES  1.00K 1% CHIP  pkg 0402  page 164 : 1 = FM_BOARD_SKU_ID2 ; 2 = GND
R1U18  RES  1.00K 1% CHIP  pkg 0402  page 164 : 1 = FM_BOARD_SKU_ID0 ; 2 = GND
R1U19  RES  20.0 1% CHIP  pkg 0402  page 159 : 1 = SMB_SMLINK0_STBY_LVC3_SCL ; 2 = SMB_SPRINGVILLE_STBY_LVC3_SCL
R1U20  RES  20.0 1% CHIP  pkg 0402  page 159 : 1 = SMB_SMLINK0_STBY_LVC3_SDA ; 2 = SMB_SPRINGVILLE_STBY_LVC3_SDA
R1U21  RES  2.7K 1% CHIP  pkg 0402  page 164 : 1 = P3V3_STBY ; 2 = FM_BOARD_SKU_ID3
R1U22  RES  2.7K 1% CHIP  pkg 0402  page 164 : 1 = P3V3_STBY ; 2 = FM_BOARD_SKU_ID1
R1U23  RES  2.7K 1% CHIP  pkg 0402  page 164 : 1 = P3V3_STBY ; 2 = FM_BOARD_SKU_ID0
R1U24  RES  2.7K 1% CHIP  pkg 0402  page 164 : 1 = P3V3_STBY ; 2 = FM_BOARD_SKU_ID2
R1U26  RES  5.11K 1% CHIP  pkg 0402  page 169 : 1 = P3V3 ; 2 = A_P3V3_SCALED
R1U27  RES  3.48K 1.0% CHIP  pkg 0402  page 169 : 1 = A_P3V3_SCALED ; 2 = GND
R1U28  1K82R2F-1-GP  1%  pkg SMD-RG  page 169 : 1 = A_P5V_SCALED ; 2 = GND
R1U29  RES  5.11K 1% CHIP  pkg 0402  page 169 : 1 = P5V ; 2 = A_P5V_SCALED
R1U30  RES  1.00K 1% CHIP  pkg 0402  page 152 : 1 = PD_DIR_2 ; 2 = GND
R1U32  RES  5.11K 1% CHIP  pkg 0402  page 169 : 1 = P12V_STBY ; 2 = A_P12V_STBY_SCALED
R1U33  649R2F-GP  1%  pkg RCL_GP  page 169 : 1 = A_P12V_STBY_SCALED ; 2 = GND
R1U34  RES  33.2 1% CHIP  pkg 0402  page 152 : 1 = H_CPU1_MEMKLM_MEMHOT_LVT3_K_N ; 2 = H_CPU1_MEMKLM_MEMHOT_LVT3_N
R1U35  RES  150.0 1% CHIP  pkg 0402  page 152 : 1 = PVCCIO_CPU1 ; 2 = H_CPU1_MEMKLM_MEMHOT_G_N
R1U36  RES  33.2 1% CHIP  pkg 0402  page 152 : 1 = H_CPU1_MEMGHJ_MEMHOT_LVT3_K_N ; 2 = H_CPU1_MEMGHJ_MEMHOT_LVT3_N
R1U37  RES  100.0 1% CHIP  pkg 0402  page 152 : 1 = P0V7_GTL2014_2 ; 2 = GND
R1U38  RES  3.48K 1.0% CHIP  pkg 0402  page 169 : 1 = A_P3V3_STBY_SCALED ; 2 = GND
R1U39  RES  5.11K 1% CHIP  pkg 0402  page 169 : 1 = P3V3_STBY ; 2 = A_P3V3_STBY_SCALED
R1U41  RES  150.0 1% CHIP  pkg 0402  page 152 : 1 = PVCCIO_CPU1 ; 2 = H_CPU1_MEMGHJ_MEMHOT_G_N
R1U43  374R2F-1-GP  1%  pkg SMD-RG  page 152 : 1 = P3V3 ; 2 = P0V7_GTL2014_2
R1U44  1K82R2F-1-GP  1%  pkg SMD-RG  page 169 : 1 = A_P5V_STBY_SCALED ; 2 = GND
R1U46  RES  33.2 1% CHIP  pkg 0402  page 152 : 1 = H_CPU0_MEMABC_MEMHOT_LVT3_K_N ; 2 = H_CPU0_MEMABC_MEMHOT_LVT3_N
R1U47  RES  5.11K 1% CHIP  pkg 0402  page 169 : 1 = P5V_STBY ; 2 = A_P5V_STBY_SCALED
R1U49  RES  2.7K 1% CHIP  pkg 0402  page 169 : 1 = P3V3_STBY ; 2 = FM_BATTERY_SENSE_EN
R1U50  RES  200.0K 1% CHIP  pkg 0402  page 169 : 1 = A_P3V_BAT_R ; 2 = P3V_BAT_SOURCE_R
R1U53  RES  0.0 5% CHIP  pkg 0402  page 152 : 1 = H_CPU1_MEMGHJ_MEMHOT_G_N ; 2 = H_CPU1_MEMGHJ_MEMHOT_G_R_N
R1U54  RES  0.0 5% CHIP  pkg 0402  page 152 : 1 = H_CPU1_MEMGHJ_MEMHOT_LVT3_N ; 2 = H_CPU1_MEMGHJ_MEMHOT_LVT3_BMC_N
R1U55  RES  0.0 5% EMPTY  pkg 0402  page 152 : 1 = H_CPU1_MEMGHJ_MEMHOT_G_N ; 2 = H_CPU1_MEMGHJ_MEMHOT_G_PCH_N
R1U56  RES  0.0 5% EMPTY  pkg 0402  page 152 : 1 = H_CPU0_MEMDEF_MEMHOT_G_PCH_N ; 2 = H_CPU0_MEMDEF_MEMHOT_G_N
R1U57  RES  0.0 5% EMPTY  pkg 0402  page 152 : 1 = H_CPU1_MEMGHJ_MEMHOT_LVT3_K_N ; 2 = H_CPU1_MEMGHJ_MEMHOT_G_PCH_N
R1U58  RES  0.0 5% CHIP  pkg 0402  page 152 : 1 = H_CPU0_MEMDEF_MEMHOT_G_N ; 2 = H_CPU0_MEMDEF_MEMHOT_G_R_N
R1U59  RES  0.0 5% CHIP  pkg 0402  page 152 : 1 = H_CPU0_ABC_MEMHOT_LVT3_R_N ; 2 = H_CPU0_MEMABC_MEMHOT_LVT3_K_N
R1U60  RES  0.0 5% CHIP  pkg 0402  page 152 : 1 = H_CPU1_MEMKLM_MEMHOT_G_N ; 2 = H_CPU1_MEMKLM_MEMHOT_G_R_N
R1U61  RES  0.0 5% EMPTY  pkg 0402  page 152 : 1 = H_CPU1_MEMKLM_MEMHOT_LVT3_K_N ; 2 = H_CPU1_MEMKLM_MEMHOT_G_PCH_N
R1U62  RES  0.0 5% EMPTY  pkg 0402  page 152 : 1 = H_CPU1_MEMKLM_MEMHOT_G_N ; 2 = H_CPU1_MEMKLM_MEMHOT_G_PCH_N
R1U63  RES  1.00K 1% CHIP  pkg 0402  page 137 : 1 = PD_RST_RTCRST_N ; 2 = GND
R1U64  RES  1.00K 1% CHIP  pkg 0402  page 137 : 1 = PD_IE_DEBUG_MODE ; 2 = GND
R1W1  1MR2F-L-GP  1%  pkg SMD-RG1  page 250 : 1 = P3V3_STBY ; 2 = FM_OCP_MEZZA_PRES_N
R1W3  1MR2F-L-GP  1%  pkg SMD-RG1  page 250 : 1 = P3V3_STBY ; 2 = FM_OCP_MEZZB_PRES_N
R1W4  RES  10.0K 1% CHIP  pkg 0402  page 250 : 1 = FM_OCP_MEZZB_PRES_LVT3_BMC ; 2 = P3V3_STBY
R1W6  1MR2F-L-GP  1%  pkg SMD-RG1  page 250 : 1 = P3V3_STBY ; 2 = FM_OCP_MEZZC_PRES_N
R1W7  RES  10.0K 1% CHIP  pkg 0402  page 250 : 1 = FM_OCP_MEZZC_PRES_LVT3_BMC ; 2 = P3V3_STBY
R1W9  RES  22.1 1.0% CHIP  pkg 0402  page 239 : 1 = PWRGD_P2V5_BMC_STBY_R ; 2 = PWRGD_P2V5_BMC_STBY
R1W10  RES  0.0 5% CHIP  pkg 0805  page 176 : 1 = P5V_STBY ; 2 = P5V_TPS2061
R1W11  RES  0.0 5% EMPTY  pkg 0805  page 176 : 1 = P5V ; 2 = P5V_TPS2061
R1W12  RES  0.0 5% CHIP  pkg 0402  page 176 : 1 = FM_CPLD_USB_P0_EN_N ; 2 = FM_USB_P0_EN_R_N
R1W13  RES  0.0 5% CHIP  pkg 0402  page 176 : 1 = FM_USB_P0_EN_BOOT_BIOS_STRAP_N ; 2 = FM_USB_P0_EN_R_N
R1W14  RES  0.0 5% CHIP  pkg 0402  page 115 : 1 = USB2_PCH_BMC_P5_DP_R ; 2 = USB2_PCH_BMC_P5_DP
R1W15  RES  0.0 5% CHIP  pkg 0402  page 115 : 1 = USB2_PCH_BMC_P5_DN_R ; 2 = USB2_PCH_BMC_P5_DN
R1W16  RES  0.0 5% CHIP  pkg 0402  page 115 : 1 = USB_PCH_BMC_P4_DP_R ; 2 = USB_PCH_BMC_P4_DP
R1W17  RES  0.0 5% CHIP  pkg 0402  page 115 : 1 = USB_PCH_BMC_P4_DN_R ; 2 = USB_PCH_BMC_P4_DN
R1W18  RES  0.0 5% CHIP  pkg 0402  page 115 : 1 = USB2_P02_DP_R ; 2 = USB2_P02_DP
R1W19  RES  0.0 5% CHIP  pkg 0402  page 115 : 1 = USB2_P02_DN_R ; 2 = USB2_P02_DN
R1W20  RES  0.0 5% CHIP  pkg 0402  page 199 : 1 = A_HSC_TEMP ; 2 = TEMP_SENSOR_B
R1W21  RES  0.0 5% CHIP  pkg 0402  page 199 : 1 = GND ; 2 = TEMP_SENSOR_E
R1W22  RES  0.0 5% CHIP  pkg 0402  page 101 : 1 = SMB_HOST_STBY_LVC3_SCL ; 2 = SMB_HOST_STBY_LVC3_SCL_R4
R1W23  RES  0.0 5% CHIP  pkg 0402  page 101 : 1 = SMB_HOST_STBY_LVC3_SDA ; 2 = SMB_HOST_STBY_LVC3_SDA_R4
R1W24  RES  0.0 5% CHIP  pkg 0402  page 101 : 1 = XTAL_CK_MNG_OUT ; 2 = XTAL_CK_MNG_OUT_R
R1W25  RES  1.00K 1% CHIP  pkg 0402  page 101 : 1 = PU_33P_33M_SMBADR ; 2 = GND
R1W26  RES  10.0K 1% EMPTY  pkg 0402  page 190 : 1 = RST_RSMRST_R_N ; 2 = GND
R1W27  RES  0.0 5% CHIP  pkg 0402  page 190 : 1 = FM_PWR_BTN_N ; 2 = FM_PWR_BTN_R2_N
